(kicad_pcb
	(version 20260206)
	(generator "pcbnew")
	(generator_version "10.0")
	(general
		(thickness 1.6)
		(legacy_teardrops no)
	)
	(paper "A4")
	(title_block
		(title "03242023_DA0F0TMBIJ0_F0T_Motherboard_J_brd_V01_OCP.brd")
		(comment 1 "Grand Teton / footprints 396-402 of 6105")
	)
	(layers
		(0 "F.Cu" signal "TOP")
		(4 "In1.Cu" signal "GND")
		(6 "In2.Cu" signal "IN1")
		(8 "In3.Cu" signal "GND1")
		(10 "In4.Cu" signal "IN2")
		(12 "In5.Cu" signal "GND2")
		(14 "In6.Cu" signal "IN3")
		(16 "In7.Cu" signal "GND3")
		(18 "In8.Cu" signal "VCC")
		(20 "In9.Cu" signal "VCC1")
		(22 "In10.Cu" signal "GND4")
		(24 "In11.Cu" signal "IN4")
		(26 "In12.Cu" signal "GND5")
		(28 "In13.Cu" signal "IN5")
		(30 "In14.Cu" signal "GND6")
		(32 "In15.Cu" signal "IN6")
		(34 "In16.Cu" signal "GND7")
		(2 "B.Cu" signal "BOTTOM")
		(9 "F.Adhes" user "F.Adhesive")
		(11 "B.Adhes" user "B.Adhesive")
		(13 "F.Paste" user "Package Geometry/Pastemask Top")
		(15 "B.Paste" user "Package Geometry/Pastemask Bottom")
		(5 "F.SilkS" user "Ref Des/Silkscreen Top")
		(7 "B.SilkS" user "Ref Des/Silkscreen Bottom")
		(1 "F.Mask" user "Board Geometry/Soldermask Top")
		(3 "B.Mask" user "Board Geometry/Soldermask Bottom")
		(17 "Dwgs.User" user "User.Drawings")
		(19 "Cmts.User" user "User.Comments")
		(21 "Eco1.User" user "User.Eco1")
		(23 "Eco2.User" user "User.Eco2")
		(25 "Edge.Cuts" user "Board Geometry/Outline")
		(27 "Margin" user)
		(31 "F.CrtYd" user "Package Geometry/Place Bound Top")
		(29 "B.CrtYd" user "Package Geometry/Place Bound Bottom")
		(35 "F.Fab" user "Ref Des/Assembly Top")
		(33 "B.Fab" user "Ref Des/Assembly Bottom")
	)
	(footprint ""
		(layer "F.Cu")
		(at 386.461 -31.968948 180)
		(property "Reference" "U322"
			(at 5.588 -0.15367 0)
			(unlocked yes)
			(layer "F.SilkS")
			(effects
				(font
					(size 0.7874 0.5842)
					(thickness 0.1524)
				)
				(justify left)
			)
		)
		(property "Value" ""
			(at 0 0 180)
			(layer "F.Fab")
			(effects
				(font
					(size 1.27 1.27)
				)
			)
		)
		(duplicate_pad_numbers_are_jumpers no)
		(fp_line
			(start 1.733296 1.549908)
			(end 1.733296 -1.549908)
			(stroke
				(width 0.1524)
				(type default)
			)
			(layer "F.SilkS")
		)
		(fp_line
			(start 1.733296 -1.549908)
			(end 0.660908 -1.549908)
			(stroke
				(width 0.1524)
				(type default)
			)
			(layer "F.SilkS")
		)
		(fp_line
			(start 0.660908 -1.549908)
			(end 0 -0.889)
			(stroke
				(width 0.1524)
				(type default)
			)
			(layer "F.SilkS")
		)
		(fp_line
			(start 0 -0.889)
			(end -0.660908 -1.549908)
			(stroke
				(width 0.1524)
				(type default)
			)
			(layer "F.SilkS")
		)
		(fp_line
			(start -0.660908 -1.549908)
			(end -1.733296 -1.549908)
			(stroke
				(width 0.1524)
				(type default)
			)
			(layer "F.SilkS")
		)
		(fp_line
			(start -1.733296 1.549908)
			(end 1.733296 1.549908)
			(stroke
				(width 0.1524)
				(type default)
			)
			(layer "F.SilkS")
		)
		(fp_line
			(start -1.733296 -1.549908)
			(end -1.733296 1.549908)
			(stroke
				(width 0.1524)
				(type default)
			)
			(layer "F.SilkS")
		)
		(fp_poly
			(pts
				(xy -2.4384 -1.20396) (xy -2.4384 -0.69596) (xy -1.9304 -0.94996)
			)
			(stroke
				(width 0)
				(type default)
			)
			(fill yes)
			(layer "F.SilkS")
		)
		(fp_line
			(start 0.849884 1.549908)
			(end 0.849884 -1.549908)
			(stroke
				(width 0.1)
				(type default)
			)
			(layer "F.Fab")
		)
		(fp_line
			(start 0.849884 -1.549908)
			(end -0.849884 -1.549908)
			(stroke
				(width 0.1)
				(type default)
			)
			(layer "F.Fab")
		)
		(fp_line
			(start -0.849884 1.549908)
			(end 0.849884 1.549908)
			(stroke
				(width 0.1)
				(type default)
			)
			(layer "F.Fab")
		)
		(fp_line
			(start -0.849884 -1.549908)
			(end -0.849884 1.549908)
			(stroke
				(width 0.1)
				(type default)
			)
			(layer "F.Fab")
		)
		(fp_poly
			(pts
				(xy -2.4384 -1.20396) (xy -2.4384 -0.69596) (xy -1.9304 -0.94996)
			)
			(stroke
				(width 0)
				(type default)
			)
			(fill yes)
			(layer "F.Fab")
		)
		(pad "1" smd rect
			(at -1.199896 -0.94996 90)
			(size 0.5588 0.8128)
			(layers "F.Cu" "F.Mask" "F.Paste")
			(net "HP_OCP_V3_1_RST_R")
		)
		(pad "2" smd rect
			(at -1.199896 0 90)
			(size 0.5588 0.8128)
			(layers "F.Cu" "F.Mask" "F.Paste")
			(net "HP_LVC3_OCP_V3_1_P12V_PWRGD")
		)
		(pad "3" smd rect
			(at -1.199896 0.94996 90)
			(size 0.5588 0.8128)
			(layers "F.Cu" "F.Mask" "F.Paste")
			(net "GND")
		)
		(pad "4" smd rect
			(at 1.199896 0.94996 90)
			(size 0.5588 0.8128)
			(layers "F.Cu" "F.Mask" "F.Paste")
			(net "HP_LVC3_OCP_V3_1_PWRGD")
		)
		(pad "5" smd rect
			(at 1.199896 -0.94996 90)
			(size 0.5588 0.8128)
			(layers "F.Cu" "F.Mask" "F.Paste")
			(net "P3V3_AUX")
		)
	)
	(footprint ""
		(layer "F.Cu")
		(at 320.190622 -59.299348)
		(property "Reference" "R1220"
			(at 0 0 0)
			(layer "F.SilkS")
			(hide yes)
			(effects
				(font
					(size 1.27 1.27)
				)
			)
		)
		(property "Value" ""
			(at 0 0 0)
			(layer "F.Fab")
			(effects
				(font
					(size 1.27 1.27)
				)
			)
		)
		(duplicate_pad_numbers_are_jumpers no)
		(fp_line
			(start -0.7874 -0.4064)
			(end 0.7874 -0.4064)
			(stroke
				(width 0.1524)
				(type default)
			)
			(layer "F.SilkS")
		)
		(fp_line
			(start -0.7874 0.4064)
			(end -0.7874 -0.4064)
			(stroke
				(width 0.1524)
				(type default)
			)
			(layer "F.SilkS")
		)
		(fp_line
			(start 0.7874 -0.4064)
			(end 0.7874 0.4064)
			(stroke
				(width 0.1524)
				(type default)
			)
			(layer "F.SilkS")
		)
		(fp_line
			(start 0.7874 0.4064)
			(end -0.7874 0.4064)
			(stroke
				(width 0.1524)
				(type default)
			)
			(layer "F.SilkS")
		)
		(fp_line
			(start -0.67945 -0.305054)
			(end -0.12065 -0.305054)
			(stroke
				(width 0.1)
				(type default)
			)
			(layer "F.Fab")
		)
		(fp_line
			(start -0.67945 0.3048)
			(end -0.67945 -0.305054)
			(stroke
				(width 0.1)
				(type default)
			)
			(layer "F.Fab")
		)
		(fp_line
			(start -0.12065 -0.305054)
			(end -0.12065 -0.2794)
			(stroke
				(width 0.1)
				(type default)
			)
			(layer "F.Fab")
		)
		(fp_line
			(start -0.12065 -0.2794)
			(end 0.12065 -0.2794)
			(stroke
				(width 0.1)
				(type default)
			)
			(layer "F.Fab")
		)
		(fp_line
			(start -0.12065 0.2794)
			(end -0.12065 0.3048)
			(stroke
				(width 0.1)
				(type default)
			)
			(layer "F.Fab")
		)
		(fp_line
			(start -0.12065 0.3048)
			(end -0.67945 0.3048)
			(stroke
				(width 0.1)
				(type default)
			)
			(layer "F.Fab")
		)
		(fp_line
			(start 0.120396 0.2794)
			(end -0.12065 0.2794)
			(stroke
				(width 0.1)
				(type default)
			)
			(layer "F.Fab")
		)
		(fp_line
			(start 0.120396 0.3048)
			(end 0.120396 0.2794)
			(stroke
				(width 0.1)
				(type default)
			)
			(layer "F.Fab")
		)
		(fp_line
			(start 0.12065 -0.3048)
			(end 0.67945 -0.3048)
			(stroke
				(width 0.1)
				(type default)
			)
			(layer "F.Fab")
		)
		(fp_line
			(start 0.12065 -0.2794)
			(end 0.12065 -0.3048)
			(stroke
				(width 0.1)
				(type default)
			)
			(layer "F.Fab")
		)
		(fp_line
			(start 0.67945 -0.3048)
			(end 0.67945 0.3048)
			(stroke
				(width 0.1)
				(type default)
			)
			(layer "F.Fab")
		)
		(fp_line
			(start 0.67945 0.3048)
			(end 0.120396 0.3048)
			(stroke
				(width 0.1)
				(type default)
			)
			(layer "F.Fab")
		)
		(pad "1" smd circle
			(at -0.40005 0)
			(size 0 0)
			(layers "F.Cu" "F.Mask" "F.Paste")
			(net "P3V3_AUX")
		)
		(pad "2" smd circle
			(at 0.40005 0)
			(size 0 0)
			(layers "F.Cu" "F.Mask" "F.Paste")
			(net "FM_PCH_MCRO_LDO")
		)
	)
	(footprint ""
		(layer "F.Cu")
		(at 333.23784 -13.718032 -90)
		(property "Reference" "C1647"
			(at 0 0 270)
			(layer "F.SilkS")
			(hide yes)
			(effects
				(font
					(size 1.27 1.27)
				)
			)
		)
		(property "Value" ""
			(at 0 0 270)
			(layer "F.Fab")
			(effects
				(font
					(size 1.27 1.27)
				)
			)
		)
		(duplicate_pad_numbers_are_jumpers no)
		(fp_line
			(start -0.7874 0.4064)
			(end -0.7874 -0.4064)
			(stroke
				(width 0.1524)
				(type default)
			)
			(layer "F.SilkS")
		)
		(fp_line
			(start 0.7874 0.4064)
			(end -0.7874 0.4064)
			(stroke
				(width 0.1524)
				(type default)
			)
			(layer "F.SilkS")
		)
		(fp_line
			(start -0.7874 -0.4064)
			(end 0.7874 -0.4064)
			(stroke
				(width 0.1524)
				(type default)
			)
			(layer "F.SilkS")
		)
		(fp_line
			(start 0.7874 -0.4064)
			(end 0.7874 0.4064)
			(stroke
				(width 0.1524)
				(type default)
			)
			(layer "F.SilkS")
		)
		(fp_line
			(start -0.67945 0.3048)
			(end -0.67945 -0.305054)
			(stroke
				(width 0.1)
				(type default)
			)
			(layer "F.Fab")
		)
		(fp_line
			(start -0.12065 0.3048)
			(end -0.67945 0.3048)
			(stroke
				(width 0.1)
				(type default)
			)
			(layer "F.Fab")
		)
		(fp_line
			(start 0.120396 0.3048)
			(end 0.120396 0.2794)
			(stroke
				(width 0.1)
				(type default)
			)
			(layer "F.Fab")
		)
		(fp_line
			(start 0.67945 0.3048)
			(end 0.120396 0.3048)
			(stroke
				(width 0.1)
				(type default)
			)
			(layer "F.Fab")
		)
		(fp_line
			(start -0.12065 0.2794)
			(end -0.12065 0.3048)
			(stroke
				(width 0.1)
				(type default)
			)
			(layer "F.Fab")
		)
		(fp_line
			(start 0.120396 0.2794)
			(end -0.12065 0.2794)
			(stroke
				(width 0.1)
				(type default)
			)
			(layer "F.Fab")
		)
		(fp_line
			(start -0.12065 -0.2794)
			(end 0.12065 -0.2794)
			(stroke
				(width 0.1)
				(type default)
			)
			(layer "F.Fab")
		)
		(fp_line
			(start 0.12065 -0.2794)
			(end 0.12065 -0.3048)
			(stroke
				(width 0.1)
				(type default)
			)
			(layer "F.Fab")
		)
		(fp_line
			(start 0.12065 -0.3048)
			(end 0.67945 -0.3048)
			(stroke
				(width 0.1)
				(type default)
			)
			(layer "F.Fab")
		)
		(fp_line
			(start 0.67945 -0.3048)
			(end 0.67945 0.3048)
			(stroke
				(width 0.1)
				(type default)
			)
			(layer "F.Fab")
		)
		(fp_line
			(start -0.67945 -0.305054)
			(end -0.12065 -0.305054)
			(stroke
				(width 0.1)
				(type default)
			)
			(layer "F.Fab")
		)
		(fp_line
			(start -0.12065 -0.305054)
			(end -0.12065 -0.2794)
			(stroke
				(width 0.1)
				(type default)
			)
			(layer "F.Fab")
		)
		(pad "1" smd circle
			(at -0.40005 0 270)
			(size 0 0)
			(layers "F.Cu" "F.Mask" "F.Paste")
			(net "P3V3_AUX")
		)
		(pad "2" smd circle
			(at 0.40005 0 270)
			(size 0 0)
			(layers "F.Cu" "F.Mask" "F.Paste")
			(net "GND")
		)
	)
	(footprint ""
		(layer "F.Cu")
		(at 331.917802 -20.77085)
		(property "Reference" "R4118"
			(at 0 0 0)
			(layer "F.SilkS")
			(hide yes)
			(effects
				(font
					(size 1.27 1.27)
				)
			)
		)
		(property "Value" ""
			(at 0 0 0)
			(layer "F.Fab")
			(effects
				(font
					(size 1.27 1.27)
				)
			)
		)
		(duplicate_pad_numbers_are_jumpers no)
		(fp_line
			(start -0.7874 -0.4064)
			(end 0.7874 -0.4064)
			(stroke
				(width 0.1524)
				(type default)
			)
			(layer "F.SilkS")
		)
		(fp_line
			(start -0.7874 0.4064)
			(end -0.7874 -0.4064)
			(stroke
				(width 0.1524)
				(type default)
			)
			(layer "F.SilkS")
		)
		(fp_line
			(start 0.7874 -0.4064)
			(end 0.7874 0.4064)
			(stroke
				(width 0.1524)
				(type default)
			)
			(layer "F.SilkS")
		)
		(fp_line
			(start 0.7874 0.4064)
			(end -0.7874 0.4064)
			(stroke
				(width 0.1524)
				(type default)
			)
			(layer "F.SilkS")
		)
		(fp_line
			(start -0.67945 -0.305054)
			(end -0.12065 -0.305054)
			(stroke
				(width 0.1)
				(type default)
			)
			(layer "F.Fab")
		)
		(fp_line
			(start -0.67945 0.3048)
			(end -0.67945 -0.305054)
			(stroke
				(width 0.1)
				(type default)
			)
			(layer "F.Fab")
		)
		(fp_line
			(start -0.12065 -0.305054)
			(end -0.12065 -0.2794)
			(stroke
				(width 0.1)
				(type default)
			)
			(layer "F.Fab")
		)
		(fp_line
			(start -0.12065 -0.2794)
			(end 0.12065 -0.2794)
			(stroke
				(width 0.1)
				(type default)
			)
			(layer "F.Fab")
		)
		(fp_line
			(start -0.12065 0.2794)
			(end -0.12065 0.3048)
			(stroke
				(width 0.1)
				(type default)
			)
			(layer "F.Fab")
		)
		(fp_line
			(start -0.12065 0.3048)
			(end -0.67945 0.3048)
			(stroke
				(width 0.1)
				(type default)
			)
			(layer "F.Fab")
		)
		(fp_line
			(start 0.120396 0.2794)
			(end -0.12065 0.2794)
			(stroke
				(width 0.1)
				(type default)
			)
			(layer "F.Fab")
		)
		(fp_line
			(start 0.120396 0.3048)
			(end 0.120396 0.2794)
			(stroke
				(width 0.1)
				(type default)
			)
			(layer "F.Fab")
		)
		(fp_line
			(start 0.12065 -0.3048)
			(end 0.67945 -0.3048)
			(stroke
				(width 0.1)
				(type default)
			)
			(layer "F.Fab")
		)
		(fp_line
			(start 0.12065 -0.2794)
			(end 0.12065 -0.3048)
			(stroke
				(width 0.1)
				(type default)
			)
			(layer "F.Fab")
		)
		(fp_line
			(start 0.67945 -0.3048)
			(end 0.67945 0.3048)
			(stroke
				(width 0.1)
				(type default)
			)
			(layer "F.Fab")
		)
		(fp_line
			(start 0.67945 0.3048)
			(end 0.120396 0.3048)
			(stroke
				(width 0.1)
				(type default)
			)
			(layer "F.Fab")
		)
		(pad "1" smd circle
			(at -0.40005 0)
			(size 0 0)
			(layers "F.Cu" "F.Mask" "F.Paste")
			(net "IRQ_LPC_SERIRQ_ESPI_CS1_N")
		)
		(pad "2" smd circle
			(at 0.40005 0)
			(size 0 0)
			(layers "F.Cu" "F.Mask" "F.Paste")
			(net "IRQ_LPC_SERIRQ_ESPI_CS1_R_N")
		)
	)
	(footprint ""
		(layer "F.Cu")
		(at 228.649784 -44.500038)
		(property "Reference" "H77"
			(at -1.143 -3.266948 0)
			(unlocked yes)
			(layer "B.SilkS")
			(effects
				(font
					(size 0.7874 0.5842)
					(thickness 0.1524)
				)
				(justify left mirror)
			)
		)
		(property "Value" ""
			(at 0 0 0)
			(layer "F.Fab")
			(effects
				(font
					(size 1.27 1.27)
				)
			)
		)
		(duplicate_pad_numbers_are_jumpers no)
		(pad "1" thru_hole rect
			(at 0 0)
			(size 4.2164 5.0038)
			(drill 2.0066
				(offset 0.099822 0)
			)
			(layers "*.Cu" "*.Mask")
			(remove_unused_layers no)
			(net "GND")
			(clearance -0.8509)
			(padstack
				(mode front_inner_back)
				(layer "Inner"
					(shape circle)
					(size 4.0132 4.0132)
					(clearance -0.7493)
				)
				(layer "B.Cu"
					(shape circle)
					(size 4.0132 4.0132)
					(clearance -0.7493)
				)
			)
		)
	)
	(footprint ""
		(layer "F.Cu")
		(at 106.3244 -251.375672 90)
		(property "Reference" "C287"
			(at 0 0 90)
			(layer "F.SilkS")
			(hide yes)
			(effects
				(font
					(size 1.27 1.27)
				)
			)
		)
		(property "Value" ""
			(at 0 0 90)
			(layer "F.Fab")
			(effects
				(font
					(size 1.27 1.27)
				)
			)
		)
		(duplicate_pad_numbers_are_jumpers no)
		(fp_line
			(start 0.7874 -0.4064)
			(end 0.7874 0.4064)
			(stroke
				(width 0.1524)
				(type default)
			)
			(layer "F.SilkS")
		)
		(fp_line
			(start -0.7874 -0.4064)
			(end 0.7874 -0.4064)
			(stroke
				(width 0.1524)
				(type default)
			)
			(layer "F.SilkS")
		)
		(fp_line
			(start 0.7874 0.4064)
			(end -0.7874 0.4064)
			(stroke
				(width 0.1524)
				(type default)
			)
			(layer "F.SilkS")
		)
		(fp_line
			(start -0.7874 0.4064)
			(end -0.7874 -0.4064)
			(stroke
				(width 0.1524)
				(type default)
			)
			(layer "F.SilkS")
		)
		(fp_line
			(start -0.12065 -0.305054)
			(end -0.12065 -0.2794)
			(stroke
				(width 0.1)
				(type default)
			)
			(layer "F.Fab")
		)
		(fp_line
			(start -0.67945 -0.305054)
			(end -0.12065 -0.305054)
			(stroke
				(width 0.1)
				(type default)
			)
			(layer "F.Fab")
		)
		(fp_line
			(start 0.67945 -0.3048)
			(end 0.67945 0.3048)
			(stroke
				(width 0.1)
				(type default)
			)
			(layer "F.Fab")
		)
		(fp_line
			(start 0.12065 -0.3048)
			(end 0.67945 -0.3048)
			(stroke
				(width 0.1)
				(type default)
			)
			(layer "F.Fab")
		)
		(fp_line
			(start 0.12065 -0.2794)
			(end 0.12065 -0.3048)
			(stroke
				(width 0.1)
				(type default)
			)
			(layer "F.Fab")
		)
		(fp_line
			(start -0.12065 -0.2794)
			(end 0.12065 -0.2794)
			(stroke
				(width 0.1)
				(type default)
			)
			(layer "F.Fab")
		)
		(fp_line
			(start 0.120396 0.2794)
			(end -0.12065 0.2794)
			(stroke
				(width 0.1)
				(type default)
			)
			(layer "F.Fab")
		)
		(fp_line
			(start -0.12065 0.2794)
			(end -0.12065 0.3048)
			(stroke
				(width 0.1)
				(type default)
			)
			(layer "F.Fab")
		)
		(fp_line
			(start 0.67945 0.3048)
			(end 0.120396 0.3048)
			(stroke
				(width 0.1)
				(type default)
			)
			(layer "F.Fab")
		)
		(fp_line
			(start 0.120396 0.3048)
			(end 0.120396 0.2794)
			(stroke
				(width 0.1)
				(type default)
			)
			(layer "F.Fab")
		)
		(fp_line
			(start -0.12065 0.3048)
			(end -0.67945 0.3048)
			(stroke
				(width 0.1)
				(type default)
			)
			(layer "F.Fab")
		)
		(fp_line
			(start -0.67945 0.3048)
			(end -0.67945 -0.305054)
			(stroke
				(width 0.1)
				(type default)
			)
			(layer "F.Fab")
		)
		(pad "1" smd circle
			(at -0.40005 0 90)
			(size 0 0)
			(layers "F.Cu" "F.Mask" "F.Paste")
			(net "PVCCIN_CPU1")
		)
		(pad "2" smd circle
			(at 0.40005 0 90)
			(size 0 0)
			(layers "F.Cu" "F.Mask" "F.Paste")
			(net "GND")
		)
	)
	(footprint ""
		(layer "F.Cu")
		(at 139.855194 -408.517344 -90)
		(property "Reference" "C1528"
			(at 0 0 270)
			(layer "F.SilkS")
			(hide yes)
			(effects
				(font
					(size 1.27 1.27)
				)
			)
		)
		(property "Value" ""
			(at 0 0 270)
			(layer "F.Fab")
			(effects
				(font
					(size 1.27 1.27)
				)
			)
		)
		(duplicate_pad_numbers_are_jumpers no)
		(fp_line
			(start -0.299974 0.150114)
			(end -0.299974 -0.150114)
			(stroke
				(width 0.1)
				(type default)
			)
			(layer "F.Fab")
		)
		(fp_line
			(start 0.299974 0.150114)
			(end -0.299974 0.150114)
			(stroke
				(width 0.1)
				(type default)
			)
			(layer "F.Fab")
		)
		(fp_line
			(start -0.299974 -0.150114)
			(end 0.299974 -0.150114)
			(stroke
				(width 0.1)
				(type default)
			)
			(layer "F.Fab")
		)
		(fp_line
			(start 0.299974 -0.150114)
			(end 0.299974 0.150114)
			(stroke
				(width 0.1)
				(type default)
			)
			(layer "F.Fab")
		)
		(pad "1" smd rect
			(at -0.2667 0 270)
			(size 0.3048 0.381)
			(layers "F.Cu" "F.Mask" "F.Paste")
			(net "P5E_CPU1_PE3_TX_C_DN<9>")
		)
		(pad "2" smd rect
			(at 0.2667 0 270)
			(size 0.3048 0.381)
			(layers "F.Cu" "F.Mask" "F.Paste")
			(net "P5E_CPU1_PE3_TX_DN<9>")
		)
	)
)
